# S9S_MB_2U (Grand Teton) — schematic netlist excerpt (pin names and nets, part order shuffled) for the footprints in the layout excerpt that follows; sources: Cadence DE-HDL packaged netlist, KiCad conversion of 03242023_DA0F0TMBIJ0_F0T_Motherboard_J_brd_V01_OCP.brd

R4531  Q_RES  0 5% CHIP  pkg 0402LF  page 241 : A = SMB_SML1_PMBUS_HSC_SDA_R3 ; B = SMB_SML1_PMBUS_HSC_SDA
R1606  Q_RES  33.2 1% CHIP  pkg 0402LF  page 213 : A = FM_OCP_SFF_PWR_GOOD ; B = FM_OCP_SFF_PWR_GOOD_R

(kicad_pcb
	(version 20260206)
	(generator "pcbnew")
	(generator_version "10.0")
	(general
		(thickness 1.6)
		(legacy_teardrops no)
	)
	(paper "A4")
	(title_block
		(title "03242023_DA0F0TMBIJ0_F0T_Motherboard_J_brd_V01_OCP.brd")
		(comment 1 "Grand Teton / footprints 279-280 of 6105")
	)
	(layers
		(0 "F.Cu" signal "TOP")
		(4 "In1.Cu" signal "GND")
		(6 "In2.Cu" signal "IN1")
		(8 "In3.Cu" signal "GND1")
		(10 "In4.Cu" signal "IN2")
		(12 "In5.Cu" signal "GND2")
		(14 "In6.Cu" signal "IN3")
		(16 "In7.Cu" signal "GND3")
		(18 "In8.Cu" signal "VCC")
		(20 "In9.Cu" signal "VCC1")
		(22 "In10.Cu" signal "GND4")
		(24 "In11.Cu" signal "IN4")
		(26 "In12.Cu" signal "GND5")
		(28 "In13.Cu" signal "IN5")
		(30 "In14.Cu" signal "GND6")
		(32 "In15.Cu" signal "IN6")
		(34 "In16.Cu" signal "GND7")
		(2 "B.Cu" signal "BOTTOM")
		(9 "F.Adhes" user "F.Adhesive")
		(11 "B.Adhes" user "B.Adhesive")
		(13 "F.Paste" user "Package Geometry/Pastemask Top")
		(15 "B.Paste" user "Package Geometry/Pastemask Bottom")
		(5 "F.SilkS" user "Ref Des/Silkscreen Top")
		(7 "B.SilkS" user "Ref Des/Silkscreen Bottom")
		(1 "F.Mask" user "Board Geometry/Soldermask Top")
		(3 "B.Mask" user "Board Geometry/Soldermask Bottom")
		(17 "Dwgs.User" user "User.Drawings")
		(19 "Cmts.User" user "User.Comments")
		(21 "Eco1.User" user "User.Eco1")
		(23 "Eco2.User" user "User.Eco2")
		(25 "Edge.Cuts" user "Board Geometry/Outline")
		(27 "Margin" user)
		(31 "F.CrtYd" user "Package Geometry/Place Bound Top")
		(29 "B.CrtYd" user "Package Geometry/Place Bound Bottom")
		(35 "F.Fab" user "Ref Des/Assembly Top")
		(33 "B.Fab" user "Ref Des/Assembly Bottom")
	)
	(footprint ""
		(layer "F.Cu")
		(at 179.09032 -408.203908)
		(property "Reference" "R4531"
			(at 0 0 0)
			(layer "F.SilkS")
			(hide yes)
			(effects
				(font
					(size 1.27 1.27)
				)
			)
		)
		(property "Value" ""
			(at 0 0 0)
			(layer "F.Fab")
			(effects
				(font
					(size 1.27 1.27)
				)
			)
		)
		(duplicate_pad_numbers_are_jumpers no)
		(fp_line
			(start -0.7874 -0.4064)
			(end 0.7874 -0.4064)
			(stroke
				(width 0.1524)
				(type default)
			)
			(layer "F.SilkS")
		)
		(fp_line
			(start -0.7874 0.4064)
			(end -0.7874 -0.4064)
			(stroke
				(width 0.1524)
				(type default)
			)
			(layer "F.SilkS")
		)
		(fp_line
			(start 0.7874 -0.4064)
			(end 0.7874 0.4064)
			(stroke
				(width 0.1524)
				(type default)
			)
			(layer "F.SilkS")
		)
		(fp_line
			(start 0.7874 0.4064)
			(end -0.7874 0.4064)
			(stroke
				(width 0.1524)
				(type default)
			)
			(layer "F.SilkS")
		)
		(fp_line
			(start -0.67945 -0.305054)
			(end -0.12065 -0.305054)
			(stroke
				(width 0.1)
				(type default)
			)
			(layer "F.Fab")
		)
		(fp_line
			(start -0.67945 0.3048)
			(end -0.67945 -0.305054)
			(stroke
				(width 0.1)
				(type default)
			)
			(layer "F.Fab")
		)
		(fp_line
			(start -0.12065 -0.305054)
			(end -0.12065 -0.2794)
			(stroke
				(width 0.1)
				(type default)
			)
			(layer "F.Fab")
		)
		(fp_line
			(start -0.12065 -0.2794)
			(end 0.12065 -0.2794)
			(stroke
				(width 0.1)
				(type default)
			)
			(layer "F.Fab")
		)
		(fp_line
			(start -0.12065 0.2794)
			(end -0.12065 0.3048)
			(stroke
				(width 0.1)
				(type default)
			)
			(layer "F.Fab")
		)
		(fp_line
			(start -0.12065 0.3048)
			(end -0.67945 0.3048)
			(stroke
				(width 0.1)
				(type default)
			)
			(layer "F.Fab")
		)
		(fp_line
			(start 0.120396 0.2794)
			(end -0.12065 0.2794)
			(stroke
				(width 0.1)
				(type default)
			)
			(layer "F.Fab")
		)
		(fp_line
			(start 0.120396 0.3048)
			(end 0.120396 0.2794)
			(stroke
				(width 0.1)
				(type default)
			)
			(layer "F.Fab")
		)
		(fp_line
			(start 0.12065 -0.3048)
			(end 0.67945 -0.3048)
			(stroke
				(width 0.1)
				(type default)
			)
			(layer "F.Fab")
		)
		(fp_line
			(start 0.12065 -0.2794)
			(end 0.12065 -0.3048)
			(stroke
				(width 0.1)
				(type default)
			)
			(layer "F.Fab")
		)
		(fp_line
			(start 0.67945 -0.3048)
			(end 0.67945 0.3048)
			(stroke
				(width 0.1)
				(type default)
			)
			(layer "F.Fab")
		)
		(fp_line
			(start 0.67945 0.3048)
			(end 0.120396 0.3048)
			(stroke
				(width 0.1)
				(type default)
			)
			(layer "F.Fab")
		)
		(pad "1" smd circle
			(at -0.40005 0)
			(size 0 0)
			(layers "F.Cu" "F.Mask" "F.Paste")
			(net "SMB_SML1_PMBUS_HSC_SDA_R3")
		)
		(pad "2" smd circle
			(at 0.40005 0)
			(size 0 0)
			(layers "F.Cu" "F.Mask" "F.Paste")
			(net "SMB_SML1_PMBUS_HSC_SDA")
		)
	)
	(footprint ""
		(layer "F.Cu")
		(at 164.64788 -109.565948)
		(property "Reference" "R1606"
			(at 0 0 0)
			(layer "F.SilkS")
			(hide yes)
			(effects
				(font
					(size 1.27 1.27)
				)
			)
		)
		(property "Value" ""
			(at 0 0 0)
			(layer "F.Fab")
			(effects
				(font
					(size 1.27 1.27)
				)
			)
		)
		(duplicate_pad_numbers_are_jumpers no)
		(fp_line
			(start -0.7874 -0.4064)
			(end 0.7874 -0.4064)
			(stroke
				(width 0.1524)
				(type default)
			)
			(layer "F.SilkS")
		)
		(fp_line
			(start -0.7874 0.4064)
			(end -0.7874 -0.4064)
			(stroke
				(width 0.1524)
				(type default)
			)
			(layer "F.SilkS")
		)
		(fp_line
			(start 0.7874 -0.4064)
			(end 0.7874 0.4064)
			(stroke
				(width 0.1524)
				(type default)
			)
			(layer "F.SilkS")
		)
		(fp_line
			(start 0.7874 0.4064)
			(end -0.7874 0.4064)
			(stroke
				(width 0.1524)
				(type default)
			)
			(layer "F.SilkS")
		)
		(fp_line
			(start -0.67945 -0.305054)
			(end -0.12065 -0.305054)
			(stroke
				(width 0.1)
				(type default)
			)
			(layer "F.Fab")
		)
		(fp_line
			(start -0.67945 0.3048)
			(end -0.67945 -0.305054)
			(stroke
				(width 0.1)
				(type default)
			)
			(layer "F.Fab")
		)
		(fp_line
			(start -0.12065 -0.305054)
			(end -0.12065 -0.2794)
			(stroke
				(width 0.1)
				(type default)
			)
			(layer "F.Fab")
		)
		(fp_line
			(start -0.12065 -0.2794)
			(end 0.12065 -0.2794)
			(stroke
				(width 0.1)
				(type default)
			)
			(layer "F.Fab")
		)
		(fp_line
			(start -0.12065 0.2794)
			(end -0.12065 0.3048)
			(stroke
				(width 0.1)
				(type default)
			)
			(layer "F.Fab")
		)
		(fp_line
			(start -0.12065 0.3048)
			(end -0.67945 0.3048)
			(stroke
				(width 0.1)
				(type default)
			)
			(layer "F.Fab")
		)
		(fp_line
			(start 0.120396 0.2794)
			(end -0.12065 0.2794)
			(stroke
				(width 0.1)
				(type default)
			)
			(layer "F.Fab")
		)
		(fp_line
			(start 0.120396 0.3048)
			(end 0.120396 0.2794)
			(stroke
				(width 0.1)
				(type default)
			)
			(layer "F.Fab")
		)
		(fp_line
			(start 0.12065 -0.3048)
			(end 0.67945 -0.3048)
			(stroke
				(width 0.1)
				(type default)
			)
			(layer "F.Fab")
		)
		(fp_line
			(start 0.12065 -0.2794)
			(end 0.12065 -0.3048)
			(stroke
				(width 0.1)
				(type default)
			)
			(layer "F.Fab")
		)
		(fp_line
			(start 0.67945 -0.3048)
			(end 0.67945 0.3048)
			(stroke
				(width 0.1)
				(type default)
			)
			(layer "F.Fab")
		)
		(fp_line
			(start 0.67945 0.3048)
			(end 0.120396 0.3048)
			(stroke
				(width 0.1)
				(type default)
			)
			(layer "F.Fab")
		)
		(pad "1" smd circle
			(at -0.40005 0)
			(size 0 0)
			(layers "F.Cu" "F.Mask" "F.Paste")
			(net "FM_OCP_SFF_PWR_GOOD")
		)
		(pad "2" smd circle
			(at 0.40005 0)
			(size 0 0)
			(layers "F.Cu" "F.Mask" "F.Paste")
			(net "FM_OCP_SFF_PWR_GOOD_R")
		)
	)
)
